(kicad_pcb
	(version 20260206)
	(generator "pcbnew")
	(generator_version "10.0")
	(general
		(thickness 1.6)
		(legacy_teardrops no)
	)
	(paper "A4")
	(title_block
		(title "01162023_DA0F0TEBIF0_F0T_Expander_BD_F_brd_V02_OCP.brd")
		(comment 1 "Grand Teton / footprints 2258-2262 of 9728")
	)
	(layers
		(0 "F.Cu" signal "TOP")
		(4 "In1.Cu" signal "GND")
		(6 "In2.Cu" signal "VCC")
		(8 "In3.Cu" signal "VCC1")
		(10 "In4.Cu" signal "GND1")
		(12 "In5.Cu" signal "IN1")
		(14 "In6.Cu" signal "GND2")
		(16 "In7.Cu" signal "IN2")
		(18 "In8.Cu" signal "GND3")
		(20 "In9.Cu" signal "IN3")
		(22 "In10.Cu" signal "GND4")
		(24 "In11.Cu" signal "IN4")
		(26 "In12.Cu" signal "GND5")
		(28 "In13.Cu" signal "IN5")
		(30 "In14.Cu" signal "GND6")
		(32 "In15.Cu" signal "IN6")
		(34 "In16.Cu" signal "GND7")
		(2 "B.Cu" signal "BOTTOM")
		(9 "F.Adhes" user "F.Adhesive")
		(11 "B.Adhes" user "B.Adhesive")
		(13 "F.Paste" user "Package Geometry/Pastemask Top")
		(15 "B.Paste" user "Package Geometry/Pastemask Bottom")
		(5 "F.SilkS" user "Ref Des/Silkscreen Top")
		(7 "B.SilkS" user "Ref Des/Silkscreen Bottom")
		(1 "F.Mask" user "Board Geometry/Soldermask Top")
		(3 "B.Mask" user "Board Geometry/Soldermask Bottom")
		(17 "Dwgs.User" user "User.Drawings")
		(19 "Cmts.User" user "User.Comments")
		(21 "Eco1.User" user "User.Eco1")
		(23 "Eco2.User" user "User.Eco2")
		(25 "Edge.Cuts" user "Board Geometry/Outline")
		(27 "Margin" user)
		(31 "F.CrtYd" user "Package Geometry/Place Bound Top")
		(29 "B.CrtYd" user "Package Geometry/Place Bound Bottom")
		(35 "F.Fab" user "Ref Des/Assembly Top")
		(33 "B.Fab" user "Ref Des/Assembly Bottom")
	)
	(footprint ""
		(layer "F.Cu")
		(at 210.942936 -188.652404 90)
		(property "Reference" "R5417"
			(at 0 0 90)
			(layer "F.SilkS")
			(hide yes)
			(effects
				(font
					(size 1.27 1.27)
				)
			)
		)
		(property "Value" ""
			(at 0 0 90)
			(layer "F.Fab")
			(effects
				(font
					(size 1.27 1.27)
				)
			)
		)
		(duplicate_pad_numbers_are_jumpers no)
		(fp_line
			(start 0.7874 -0.4064)
			(end 0.7874 0.4064)
			(stroke
				(width 0.1524)
				(type default)
			)
			(layer "F.SilkS")
		)
		(fp_line
			(start -0.7874 -0.4064)
			(end 0.7874 -0.4064)
			(stroke
				(width 0.1524)
				(type default)
			)
			(layer "F.SilkS")
		)
		(fp_line
			(start 0.7874 0.4064)
			(end -0.7874 0.4064)
			(stroke
				(width 0.1524)
				(type default)
			)
			(layer "F.SilkS")
		)
		(fp_line
			(start -0.7874 0.4064)
			(end -0.7874 -0.4064)
			(stroke
				(width 0.1524)
				(type default)
			)
			(layer "F.SilkS")
		)
		(fp_line
			(start -0.12065 -0.305054)
			(end -0.12065 -0.2794)
			(stroke
				(width 0.1)
				(type default)
			)
			(layer "F.Fab")
		)
		(fp_line
			(start -0.67945 -0.305054)
			(end -0.12065 -0.305054)
			(stroke
				(width 0.1)
				(type default)
			)
			(layer "F.Fab")
		)
		(fp_line
			(start 0.67945 -0.3048)
			(end 0.67945 0.3048)
			(stroke
				(width 0.1)
				(type default)
			)
			(layer "F.Fab")
		)
		(fp_line
			(start 0.12065 -0.3048)
			(end 0.67945 -0.3048)
			(stroke
				(width 0.1)
				(type default)
			)
			(layer "F.Fab")
		)
		(fp_line
			(start 0.12065 -0.2794)
			(end 0.12065 -0.3048)
			(stroke
				(width 0.1)
				(type default)
			)
			(layer "F.Fab")
		)
		(fp_line
			(start -0.12065 -0.2794)
			(end 0.12065 -0.2794)
			(stroke
				(width 0.1)
				(type default)
			)
			(layer "F.Fab")
		)
		(fp_line
			(start 0.120396 0.2794)
			(end -0.12065 0.2794)
			(stroke
				(width 0.1)
				(type default)
			)
			(layer "F.Fab")
		)
		(fp_line
			(start -0.12065 0.2794)
			(end -0.12065 0.3048)
			(stroke
				(width 0.1)
				(type default)
			)
			(layer "F.Fab")
		)
		(fp_line
			(start 0.67945 0.3048)
			(end 0.120396 0.3048)
			(stroke
				(width 0.1)
				(type default)
			)
			(layer "F.Fab")
		)
		(fp_line
			(start 0.120396 0.3048)
			(end 0.120396 0.2794)
			(stroke
				(width 0.1)
				(type default)
			)
			(layer "F.Fab")
		)
		(fp_line
			(start -0.12065 0.3048)
			(end -0.67945 0.3048)
			(stroke
				(width 0.1)
				(type default)
			)
			(layer "F.Fab")
		)
		(fp_line
			(start -0.67945 0.3048)
			(end -0.67945 -0.305054)
			(stroke
				(width 0.1)
				(type default)
			)
			(layer "F.Fab")
		)
		(pad "1" smd circle
			(at -0.40005 0 90)
			(size 0 0)
			(layers "F.Cu" "F.Mask" "F.Paste")
			(net "BIC_SEL_FLASH_SW3_R")
		)
		(pad "2" smd circle
			(at 0.40005 0 90)
			(size 0 0)
			(layers "F.Cu" "F.Mask" "F.Paste")
			(net "GND")
		)
	)
	(footprint ""
		(layer "F.Cu")
		(at 166.293292 -172.004482 -90)
		(property "Reference" "U21"
			(at 1.519682 -2.414778 90)
			(unlocked yes)
			(layer "F.SilkS")
			(effects
				(font
					(size 0.7874 0.5842)
					(thickness 0.1524)
				)
				(justify left)
			)
		)
		(property "Value" ""
			(at 0 0 270)
			(layer "F.Fab")
			(effects
				(font
					(size 1.27 1.27)
				)
			)
		)
		(duplicate_pad_numbers_are_jumpers no)
		(fp_line
			(start -2.0574 1.651)
			(end -2.0574 -1.651)
			(stroke
				(width 0.1524)
				(type default)
			)
			(layer "F.SilkS")
		)
		(fp_line
			(start 2.0574 1.651)
			(end -2.0574 1.651)
			(stroke
				(width 0.1524)
				(type default)
			)
			(layer "F.SilkS")
		)
		(fp_line
			(start 0 -1.016)
			(end 0.381 -1.651)
			(stroke
				(width 0.1524)
				(type default)
			)
			(layer "F.SilkS")
		)
		(fp_line
			(start -2.0574 -1.651)
			(end -0.381 -1.651)
			(stroke
				(width 0.1524)
				(type default)
			)
			(layer "F.SilkS")
		)
		(fp_line
			(start -0.381 -1.651)
			(end 0 -1.016)
			(stroke
				(width 0.1524)
				(type default)
			)
			(layer "F.SilkS")
		)
		(fp_line
			(start 0.381 -1.651)
			(end 2.0574 -1.651)
			(stroke
				(width 0.1524)
				(type default)
			)
			(layer "F.SilkS")
		)
		(fp_line
			(start 2.0574 -1.651)
			(end 2.0574 1.651)
			(stroke
				(width 0.1524)
				(type default)
			)
			(layer "F.SilkS")
		)
		(fp_poly
			(pts
				(xy -2.71272 -0.719328) (xy -2.71272 -1.344168) (xy -2.159 -1.016)
			)
			(stroke
				(width 0)
				(type default)
			)
			(fill yes)
			(layer "F.SilkS")
		)
		(fp_line
			(start -0.899922 1.549908)
			(end -0.899922 1.199896)
			(stroke
				(width 0.1)
				(type default)
			)
			(layer "F.Fab")
		)
		(fp_line
			(start 0.899922 1.549908)
			(end -0.899922 1.549908)
			(stroke
				(width 0.1)
				(type default)
			)
			(layer "F.Fab")
		)
		(fp_line
			(start -1.599946 1.199896)
			(end -1.599946 -1.199896)
			(stroke
				(width 0.1)
				(type default)
			)
			(layer "F.Fab")
		)
		(fp_line
			(start -0.899922 1.199896)
			(end -1.599946 1.199896)
			(stroke
				(width 0.1)
				(type default)
			)
			(layer "F.Fab")
		)
		(fp_line
			(start 0.899922 1.199896)
			(end 0.899922 1.549908)
			(stroke
				(width 0.1)
				(type default)
			)
			(layer "F.Fab")
		)
		(fp_line
			(start 1.599946 1.199896)
			(end 0.899922 1.199896)
			(stroke
				(width 0.1)
				(type default)
			)
			(layer "F.Fab")
		)
		(fp_line
			(start -1.599946 -1.199896)
			(end -0.899922 -1.199896)
			(stroke
				(width 0.1)
				(type default)
			)
			(layer "F.Fab")
		)
		(fp_line
			(start -0.899922 -1.199896)
			(end -0.899922 -1.549908)
			(stroke
				(width 0.1)
				(type default)
			)
			(layer "F.Fab")
		)
		(fp_line
			(start 0.899922 -1.199896)
			(end 1.599946 -1.199896)
			(stroke
				(width 0.1)
				(type default)
			)
			(layer "F.Fab")
		)
		(fp_line
			(start 1.599946 -1.199896)
			(end 1.599946 1.199896)
			(stroke
				(width 0.1)
				(type default)
			)
			(layer "F.Fab")
		)
		(fp_line
			(start -0.899922 -1.549908)
			(end 0.899922 -1.549908)
			(stroke
				(width 0.1)
				(type default)
			)
			(layer "F.Fab")
		)
		(fp_line
			(start 0.899922 -1.549908)
			(end 0.899922 -1.199896)
			(stroke
				(width 0.1)
				(type default)
			)
			(layer "F.Fab")
		)
		(fp_poly
			(pts
				(xy -2.71272 -0.719328) (xy -2.71272 -1.344168) (xy -2.159 -1.016)
			)
			(stroke
				(width 0)
				(type default)
			)
			(fill yes)
			(layer "F.Fab")
		)
		(pad "1" smd rect
			(at -1.225042 -0.94996 180)
			(size 0.5588 1.3462)
			(layers "F.Cu" "F.Mask" "F.Paste")
			(net "HP_NIC2_PWRGD_R")
		)
		(pad "2" smd rect
			(at -1.225042 0 180)
			(size 0.5588 1.3462)
			(layers "F.Cu" "F.Mask" "F.Paste")
			(net "RST_NIC2_PERST_R_N")
		)
		(pad "3" smd rect
			(at -1.225042 0.94996 180)
			(size 0.5588 1.3462)
			(layers "F.Cu" "F.Mask" "F.Paste")
			(net "GND")
		)
		(pad "4" smd rect
			(at 1.225042 0.94996 180)
			(size 0.5588 1.3462)
			(layers "F.Cu" "F.Mask" "F.Paste")
			(net "RST_HP_NIC2_N")
		)
		(pad "5" smd rect
			(at 1.225042 -0.94996 180)
			(size 0.5588 1.3462)
			(layers "F.Cu" "F.Mask" "F.Paste")
			(net "P3V3_AUX")
		)
	)
	(footprint ""
		(layer "F.Cu")
		(at 5.589524 -63.56223)
		(property "Reference" "Q127"
			(at 0.009144 -1.86563 0)
			(unlocked yes)
			(layer "F.SilkS")
			(effects
				(font
					(size 0.7874 0.5842)
					(thickness 0.1524)
				)
			)
		)
		(property "Value" ""
			(at 0 0 0)
			(layer "F.Fab")
			(effects
				(font
					(size 1.27 1.27)
				)
			)
		)
		(duplicate_pad_numbers_are_jumpers no)
		(fp_line
			(start -1.376172 -1.199896)
			(end -0.508 -1.199896)
			(stroke
				(width 0.1524)
				(type default)
			)
			(layer "F.SilkS")
		)
		(fp_line
			(start -1.376172 1.199896)
			(end -1.376172 -1.199896)
			(stroke
				(width 0.1524)
				(type default)
			)
			(layer "F.SilkS")
		)
		(fp_line
			(start -0.508 -1.199896)
			(end 0 -0.762)
			(stroke
				(width 0.1524)
				(type default)
			)
			(layer "F.SilkS")
		)
		(fp_line
			(start 0 -0.762)
			(end 0.508 -1.199896)
			(stroke
				(width 0.1524)
				(type default)
			)
			(layer "F.SilkS")
		)
		(fp_line
			(start 0.508 -1.199896)
			(end 1.376172 -1.199896)
			(stroke
				(width 0.1524)
				(type default)
			)
			(layer "F.SilkS")
		)
		(fp_line
			(start 1.376172 -1.199896)
			(end 1.376172 1.199896)
			(stroke
				(width 0.1524)
				(type default)
			)
			(layer "F.SilkS")
		)
		(fp_line
			(start 1.376172 1.199896)
			(end -1.376172 1.199896)
			(stroke
				(width 0.1524)
				(type default)
			)
			(layer "F.SilkS")
		)
		(fp_poly
			(pts
				(xy -1.574546 -1.051814) (xy -1.843786 -1.860042) (xy -2.382774 -1.321308)
			)
			(stroke
				(width 0)
				(type default)
			)
			(fill yes)
			(layer "F.SilkS")
		)
		(fp_line
			(start -0.674878 -1.100074)
			(end 0.674878 -1.100074)
			(stroke
				(width 0.1)
				(type default)
			)
			(layer "F.Fab")
		)
		(fp_line
			(start -0.674878 1.100074)
			(end -0.674878 -1.100074)
			(stroke
				(width 0.1)
				(type default)
			)
			(layer "F.Fab")
		)
		(fp_line
			(start 0.674878 -1.100074)
			(end 0.674878 1.100074)
			(stroke
				(width 0.1)
				(type default)
			)
			(layer "F.Fab")
		)
		(fp_line
			(start 0.674878 1.100074)
			(end -0.674878 1.100074)
			(stroke
				(width 0.1)
				(type default)
			)
			(layer "F.Fab")
		)
		(fp_poly
			(pts
				(xy -1.4605 -0.7493) (xy -2.2225 -1.1303) (xy -2.2225 -0.3683)
			)
			(stroke
				(width 0)
				(type default)
			)
			(fill yes)
			(layer "F.Fab")
		)
		(pad "1" smd rect
			(at -0.899922 -0.750062 270)
			(size 0.6096 0.6096)
			(layers "F.Cu" "F.Mask" "F.Paste")
			(net "GND")
		)
		(pad "2" smd rect
			(at -0.899922 0 270)
			(size 0.4064 0.6096)
			(layers "F.Cu" "F.Mask" "F.Paste")
			(net "P12V_SSD0_PG_G1")
		)
		(pad "3" smd rect
			(at -0.899922 0.750062 270)
			(size 0.6096 0.6096)
			(layers "F.Cu" "F.Mask" "F.Paste")
			(net "PWRGD_P12V_SSD0_D")
		)
		(pad "4" smd rect
			(at 0.899922 0.750062 270)
			(size 0.6096 0.6096)
			(layers "F.Cu" "F.Mask" "F.Paste")
			(net "GND")
		)
		(pad "5" smd rect
			(at 0.899922 0 270)
			(size 0.4064 0.6096)
			(layers "F.Cu" "F.Mask" "F.Paste")
			(net "P12V_SSD0_PG_G2")
		)
		(pad "6" smd rect
			(at 0.899922 -0.750062 270)
			(size 0.6096 0.6096)
			(layers "F.Cu" "F.Mask" "F.Paste")
			(net "P12V_SSD0_PG_G2")
		)
	)
	(footprint ""
		(layer "F.Cu")
		(at 336.042 -153.67)
		(property "Reference" "R4794"
			(at 0 0 0)
			(layer "F.SilkS")
			(hide yes)
			(effects
				(font
					(size 1.27 1.27)
				)
			)
		)
		(property "Value" ""
			(at 0 0 0)
			(layer "F.Fab")
			(effects
				(font
					(size 1.27 1.27)
				)
			)
		)
		(duplicate_pad_numbers_are_jumpers no)
		(fp_line
			(start -0.7874 -0.4064)
			(end 0.7874 -0.4064)
			(stroke
				(width 0.1524)
				(type default)
			)
			(layer "F.SilkS")
		)
		(fp_line
			(start -0.7874 0.4064)
			(end -0.7874 -0.4064)
			(stroke
				(width 0.1524)
				(type default)
			)
			(layer "F.SilkS")
		)
		(fp_line
			(start 0.7874 -0.4064)
			(end 0.7874 0.4064)
			(stroke
				(width 0.1524)
				(type default)
			)
			(layer "F.SilkS")
		)
		(fp_line
			(start 0.7874 0.4064)
			(end -0.7874 0.4064)
			(stroke
				(width 0.1524)
				(type default)
			)
			(layer "F.SilkS")
		)
		(fp_line
			(start -0.67945 -0.305054)
			(end -0.12065 -0.305054)
			(stroke
				(width 0.1)
				(type default)
			)
			(layer "F.Fab")
		)
		(fp_line
			(start -0.67945 0.3048)
			(end -0.67945 -0.305054)
			(stroke
				(width 0.1)
				(type default)
			)
			(layer "F.Fab")
		)
		(fp_line
			(start -0.12065 -0.305054)
			(end -0.12065 -0.2794)
			(stroke
				(width 0.1)
				(type default)
			)
			(layer "F.Fab")
		)
		(fp_line
			(start -0.12065 -0.2794)
			(end 0.12065 -0.2794)
			(stroke
				(width 0.1)
				(type default)
			)
			(layer "F.Fab")
		)
		(fp_line
			(start -0.12065 0.2794)
			(end -0.12065 0.3048)
			(stroke
				(width 0.1)
				(type default)
			)
			(layer "F.Fab")
		)
		(fp_line
			(start -0.12065 0.3048)
			(end -0.67945 0.3048)
			(stroke
				(width 0.1)
				(type default)
			)
			(layer "F.Fab")
		)
		(fp_line
			(start 0.120396 0.2794)
			(end -0.12065 0.2794)
			(stroke
				(width 0.1)
				(type default)
			)
			(layer "F.Fab")
		)
		(fp_line
			(start 0.120396 0.3048)
			(end 0.120396 0.2794)
			(stroke
				(width 0.1)
				(type default)
			)
			(layer "F.Fab")
		)
		(fp_line
			(start 0.12065 -0.3048)
			(end 0.67945 -0.3048)
			(stroke
				(width 0.1)
				(type default)
			)
			(layer "F.Fab")
		)
		(fp_line
			(start 0.12065 -0.2794)
			(end 0.12065 -0.3048)
			(stroke
				(width 0.1)
				(type default)
			)
			(layer "F.Fab")
		)
		(fp_line
			(start 0.67945 -0.3048)
			(end 0.67945 0.3048)
			(stroke
				(width 0.1)
				(type default)
			)
			(layer "F.Fab")
		)
		(fp_line
			(start 0.67945 0.3048)
			(end 0.120396 0.3048)
			(stroke
				(width 0.1)
				(type default)
			)
			(layer "F.Fab")
		)
		(pad "1" smd circle
			(at -0.40005 0)
			(size 0 0)
			(layers "F.Cu" "F.Mask" "F.Paste")
			(net "P3V3_AUX")
		)
		(pad "2" smd circle
			(at 0.40005 0)
			(size 0 0)
			(layers "F.Cu" "F.Mask" "F.Paste")
			(net "RST_PEX_SSD13_PERST_R_N")
		)
	)
	(footprint ""
		(layer "F.Cu")
		(at 238.738664 -206.51216 -90)
		(property "Reference" "R4851"
			(at 0 0 270)
			(layer "F.SilkS")
			(hide yes)
			(effects
				(font
					(size 1.27 1.27)
				)
			)
		)
		(property "Value" ""
			(at 0 0 270)
			(layer "F.Fab")
			(effects
				(font
					(size 1.27 1.27)
				)
			)
		)
		(duplicate_pad_numbers_are_jumpers no)
		(fp_line
			(start -0.7874 0.4064)
			(end -0.7874 -0.4064)
			(stroke
				(width 0.1524)
				(type default)
			)
			(layer "F.SilkS")
		)
		(fp_line
			(start 0.7874 0.4064)
			(end -0.7874 0.4064)
			(stroke
				(width 0.1524)
				(type default)
			)
			(layer "F.SilkS")
		)
		(fp_line
			(start -0.7874 -0.4064)
			(end 0.7874 -0.4064)
			(stroke
				(width 0.1524)
				(type default)
			)
			(layer "F.SilkS")
		)
		(fp_line
			(start 0.7874 -0.4064)
			(end 0.7874 0.4064)
			(stroke
				(width 0.1524)
				(type default)
			)
			(layer "F.SilkS")
		)
		(fp_line
			(start -0.67945 0.3048)
			(end -0.67945 -0.305054)
			(stroke
				(width 0.1)
				(type default)
			)
			(layer "F.Fab")
		)
		(fp_line
			(start -0.12065 0.3048)
			(end -0.67945 0.3048)
			(stroke
				(width 0.1)
				(type default)
			)
			(layer "F.Fab")
		)
		(fp_line
			(start 0.120396 0.3048)
			(end 0.120396 0.2794)
			(stroke
				(width 0.1)
				(type default)
			)
			(layer "F.Fab")
		)
		(fp_line
			(start 0.67945 0.3048)
			(end 0.120396 0.3048)
			(stroke
				(width 0.1)
				(type default)
			)
			(layer "F.Fab")
		)
		(fp_line
			(start -0.12065 0.2794)
			(end -0.12065 0.3048)
			(stroke
				(width 0.1)
				(type default)
			)
			(layer "F.Fab")
		)
		(fp_line
			(start 0.120396 0.2794)
			(end -0.12065 0.2794)
			(stroke
				(width 0.1)
				(type default)
			)
			(layer "F.Fab")
		)
		(fp_line
			(start -0.12065 -0.2794)
			(end 0.12065 -0.2794)
			(stroke
				(width 0.1)
				(type default)
			)
			(layer "F.Fab")
		)
		(fp_line
			(start 0.12065 -0.2794)
			(end 0.12065 -0.3048)
			(stroke
				(width 0.1)
				(type default)
			)
			(layer "F.Fab")
		)
		(fp_line
			(start 0.12065 -0.3048)
			(end 0.67945 -0.3048)
			(stroke
				(width 0.1)
				(type default)
			)
			(layer "F.Fab")
		)
		(fp_line
			(start 0.67945 -0.3048)
			(end 0.67945 0.3048)
			(stroke
				(width 0.1)
				(type default)
			)
			(layer "F.Fab")
		)
		(fp_line
			(start -0.67945 -0.305054)
			(end -0.12065 -0.305054)
			(stroke
				(width 0.1)
				(type default)
			)
			(layer "F.Fab")
		)
		(fp_line
			(start -0.12065 -0.305054)
			(end -0.12065 -0.2794)
			(stroke
				(width 0.1)
				(type default)
			)
			(layer "F.Fab")
		)
		(pad "1" smd circle
			(at -0.40005 0 270)
			(size 0 0)
			(layers "F.Cu" "F.Mask" "F.Paste")
			(net "P12V_AUX_SCALED")
		)
		(pad "2" smd circle
			(at 0.40005 0 270)
			(size 0 0)
			(layers "F.Cu" "F.Mask" "F.Paste")
			(net "GND")
		)
	)
)
